(kicad_pcb
	(version 20260206)
	(generator "pcbnew")
	(generator_version "10.0")
	(general
		(thickness 1.6)
		(legacy_teardrops no)
	)
	(paper "A4")
	(title_block
		(title "netronome-mezz — pcbd0082-001_rev01_jul9_a.brd")
		(comment 1 "Open CloudServer (Microsoft) / footprints 33-38 of 714")
	)
	(layers
		(0 "F.Cu" signal "TOP")
		(4 "In1.Cu" signal "02_GND")
		(6 "In2.Cu" signal "03_SIG")
		(8 "In3.Cu" signal "04_SIG")
		(10 "In4.Cu" signal "05_GND")
		(12 "In5.Cu" signal "06_PWR1")
		(14 "In6.Cu" signal "07_SIG")
		(16 "In7.Cu" signal "08_SIG")
		(18 "In8.Cu" signal "09_GND")
		(2 "B.Cu" signal "BOTTOM")
		(9 "F.Adhes" user "F.Adhesive")
		(11 "B.Adhes" user "B.Adhesive")
		(13 "F.Paste" user "Package Geometry/Pastemask Top")
		(15 "B.Paste" user "Package Geometry/Pastemask Bottom")
		(5 "F.SilkS" user "Ref Des/Silkscreen Top")
		(7 "B.SilkS" user "Ref Des/Silkscreen Bottom")
		(1 "F.Mask" user "Board Geometry/Soldermask Top")
		(3 "B.Mask" user "Board Geometry/Soldermask Bottom")
		(17 "Dwgs.User" user "User.Drawings")
		(19 "Cmts.User" user "User.Comments")
		(21 "Eco1.User" user "User.Eco1")
		(23 "Eco2.User" user "User.Eco2")
		(25 "Edge.Cuts" user "Board Geometry/Outline")
		(27 "Margin" user)
		(31 "F.CrtYd" user "Package Geometry/Place Bound Top")
		(29 "B.CrtYd" user "Package Geometry/Place Bound Bottom")
		(35 "F.Fab" user "Ref Des/Assembly Top")
		(33 "B.Fab" user "Ref Des/Assembly Bottom")
		(45 "User.4" user "COMPVAL_TYPE_BOTTOM")
	)
	(footprint ""
		(layer "F.Cu")
		(at 44.196 54.737)
		(property "Reference" "D5"
			(at -1.143 1.93167 0)
			(unlocked yes)
			(layer "F.SilkS")
			(effects
				(font
					(size 0.7874 0.5842)
					(thickness 0.127)
				)
				(justify left)
			)
		)
		(property "Value" "LL4148"
			(at 0.1524 -0.148158 0)
			(unlocked yes)
			(layer "F.Fab")
			(hide yes)
			(effects
				(font
					(size 1.27 0.9652)
					(thickness 0.000001)
				)
				(justify left)
			)
		)
		(property "Device Type" "DIOD0001V"
			(at 0.1524 -0.148158 0)
			(unlocked yes)
			(layer "F.Fab")
			(hide yes)
			(effects
				(font
					(size 1.27 0.9652)
					(thickness 0.000001)
				)
				(justify left)
			)
		)
		(duplicate_pad_numbers_are_jumpers no)
		(fp_line
			(start -2.667 -1.143)
			(end -2.667 1.143)
			(stroke
				(width 0.1524)
				(type default)
			)
			(layer "F.SilkS")
		)
		(fp_line
			(start -2.667 -1.143)
			(end -2.667 1.143)
			(stroke
				(width 0.1524)
				(type default)
			)
			(layer "F.SilkS")
		)
		(fp_line
			(start -2.667 1.143)
			(end -2.286 1.143)
			(stroke
				(width 0.1524)
				(type default)
			)
			(layer "F.SilkS")
		)
		(fp_line
			(start -2.54 -1.143)
			(end -2.54 1.143)
			(stroke
				(width 0.1524)
				(type default)
			)
			(layer "F.SilkS")
		)
		(fp_line
			(start -2.54 -1.143)
			(end -2.54 1.143)
			(stroke
				(width 0.1524)
				(type default)
			)
			(layer "F.SilkS")
		)
		(fp_line
			(start -2.413 -1.143)
			(end 1.778 -1.143)
			(stroke
				(width 0.1524)
				(type default)
			)
			(layer "F.SilkS")
		)
		(fp_line
			(start -2.413 1.143)
			(end -2.413 -1.143)
			(stroke
				(width 0.1524)
				(type default)
			)
			(layer "F.SilkS")
		)
		(fp_line
			(start -2.286 -1.143)
			(end -2.667 -1.143)
			(stroke
				(width 0.1524)
				(type default)
			)
			(layer "F.SilkS")
		)
		(fp_line
			(start 0.8128 1.143)
			(end -0.8128 1.143)
			(stroke
				(width 0.1524)
				(type default)
			)
			(layer "F.SilkS")
		)
		(fp_line
			(start 1.905 1.143)
			(end -2.413 1.143)
			(stroke
				(width 0.1524)
				(type default)
			)
			(layer "F.SilkS")
		)
		(fp_poly
			(pts
				(xy -2.794 -1.397) (xy 2.667 -1.397) (xy 2.667 0.762) (xy -2.794 0.762)
			)
			(stroke
				(width 0)
				(type default)
			)
			(fill no)
			(layer "F.CrtYd")
		)
		(fp_line
			(start -1.8542 -0.8001)
			(end -1.8542 0.8001)
			(stroke
				(width 0.1524)
				(type default)
			)
			(layer "F.Fab")
		)
		(fp_line
			(start -1.8542 0.8001)
			(end 1.8542 0.8001)
			(stroke
				(width 0.1524)
				(type default)
			)
			(layer "F.Fab")
		)
		(fp_line
			(start -1.397 -0.762)
			(end -1.143 -0.762)
			(stroke
				(width 0.1524)
				(type default)
			)
			(layer "F.Fab")
		)
		(fp_line
			(start -1.397 0.762)
			(end -1.397 -0.762)
			(stroke
				(width 0.1524)
				(type default)
			)
			(layer "F.Fab")
		)
		(fp_line
			(start -1.143 -0.762)
			(end -1.143 0.762)
			(stroke
				(width 0.1524)
				(type default)
			)
			(layer "F.Fab")
		)
		(fp_line
			(start 1.8542 -0.8001)
			(end -1.8542 -0.8001)
			(stroke
				(width 0.1524)
				(type default)
			)
			(layer "F.Fab")
		)
		(fp_line
			(start 1.8542 0.8001)
			(end 1.8542 -0.8001)
			(stroke
				(width 0.1524)
				(type default)
			)
			(layer "F.Fab")
		)
		(fp_poly
			(pts
				(xy -1.8542 -0.7874) (xy -1.8542 0.8128) (xy -1.143 0.8128) (xy -1.143 -0.7874)
			)
			(stroke
				(width 0)
				(type default)
			)
			(fill yes)
			(layer "F.Fab")
		)
		(fp_text user "C"
			(at -3.7846 0.196012 0)
			(unlocked yes)
			(layer "F.SilkS")
			(effects
				(font
					(size 0.7874 0.5842)
					(thickness 0.127)
				)
				(justify left)
			)
		)
		(fp_text user "A"
			(at 2.3114 0.196012 0)
			(unlocked yes)
			(layer "F.SilkS")
			(effects
				(font
					(size 0.7874 0.5842)
					(thickness 0.127)
				)
				(justify left)
			)
		)
		(fp_text user "C"
			(at -1.905 1.55067 0)
			(unlocked yes)
			(layer "F.Fab")
			(effects
				(font
					(size 0.7874 0.5842)
					(thickness 0.127)
				)
				(justify left)
			)
		)
		(fp_text user "A"
			(at 1.143 1.42367 0)
			(unlocked yes)
			(layer "F.Fab")
			(effects
				(font
					(size 0.7874 0.5842)
					(thickness 0.127)
				)
				(justify left)
			)
		)
		(pad "1" smd rect
			(at 1.651 0)
			(size 1.016 1.7018)
			(layers "F.Cu" "F.Mask" "F.Paste")
			(net "0.7V_REF")
		)
		(pad "2" smd rect
			(at -1.651 0)
			(size 1.016 1.7018)
			(layers "F.Cu" "F.Mask" "F.Paste")
			(net "GND")
		)
	)
	(footprint ""
		(layer "F.Cu")
		(at 77.978 7.874 180)
		(property "Reference" "C213"
			(at -0.762 0.35433 0)
			(unlocked yes)
			(layer "F.SilkS")
			(effects
				(font
					(size 0.7874 0.5842)
					(thickness 0.127)
				)
				(justify left)
			)
		)
		(property "Value" "1UF"
			(at -0.091846 0.2921 270)
			(unlocked yes)
			(layer "F.Fab")
			(hide yes)
			(effects
				(font
					(size 0.7874 0.5842)
					(thickness 0.2032)
				)
				(justify left)
			)
		)
		(property "Device Type" "CAPC0028"
			(at -0.091846 0.2921 270)
			(unlocked yes)
			(layer "F.Fab")
			(hide yes)
			(effects
				(font
					(size 0.7874 0.5842)
					(thickness 0.2032)
				)
				(justify left)
			)
		)
		(duplicate_pad_numbers_are_jumpers no)
		(fp_poly
			(pts
				(xy 0.635 1.0668) (xy 0.635 -1.0668) (xy -0.635 -1.0668) (xy -0.635 1.0668)
			)
			(stroke
				(width 0)
				(type default)
			)
			(fill no)
			(layer "F.CrtYd")
		)
		(fp_line
			(start 0.254 0.508)
			(end -0.254 0.508)
			(stroke
				(width 0.0254)
				(type default)
			)
			(layer "F.Fab")
		)
		(fp_line
			(start 0.254 -0.508)
			(end 0.254 0.508)
			(stroke
				(width 0.0254)
				(type default)
			)
			(layer "F.Fab")
		)
		(fp_line
			(start -0.254 0.508)
			(end -0.254 -0.508)
			(stroke
				(width 0.0254)
				(type default)
			)
			(layer "F.Fab")
		)
		(fp_line
			(start -0.254 -0.508)
			(end 0.254 -0.508)
			(stroke
				(width 0.0254)
				(type default)
			)
			(layer "F.Fab")
		)
		(pad "1" smd rect
			(at 0 -0.4191 180)
			(size 0.508 0.5334)
			(layers "F.Cu" "F.Mask" "F.Paste")
			(net "DDR_VDDQ")
		)
		(pad "2" smd rect
			(at 0 0.4191 180)
			(size 0.508 0.5334)
			(layers "F.Cu" "F.Mask" "F.Paste")
			(net "GND")
		)
		(zone
			(layer "F.Cu")
			(hatch none 0.5)
			(connect_pads
				(clearance 0)
			)
			(min_thickness 0.25)
			(keepout
				(tracks not_allowed)
				(vias allowed)
				(pads allowed)
				(copperpour not_allowed)
				(footprints allowed)
			)
			(placement
				(enabled no)
				(sheetname "")
			)
			(fill
				(thermal_gap 0.5)
				(thermal_bridge_width 0.5)
				(island_removal_mode 0)
			)
			(polygon
				(pts
					(xy 77.9526 7.8994) (xy 77.9526 7.8486) (xy 78.0034 7.8486) (xy 78.0034 7.8994)
				)
			)
		)
	)
	(footprint ""
		(layer "F.Cu")
		(at 73.406 23.495 90)
		(property "Reference" "C217"
			(at -0.78867 -0.254 0)
			(unlocked yes)
			(layer "F.SilkS")
			(effects
				(font
					(size 0.7874 0.5842)
					(thickness 0.127)
				)
				(justify left)
			)
		)
		(property "Value" "1UF"
			(at -0.091846 0.2921 180)
			(unlocked yes)
			(layer "F.Fab")
			(hide yes)
			(effects
				(font
					(size 0.7874 0.5842)
					(thickness 0.2032)
				)
				(justify left)
			)
		)
		(property "Device Type" "CAPC0028"
			(at -0.091846 0.2921 180)
			(unlocked yes)
			(layer "F.Fab")
			(hide yes)
			(effects
				(font
					(size 0.7874 0.5842)
					(thickness 0.2032)
				)
				(justify left)
			)
		)
		(duplicate_pad_numbers_are_jumpers no)
		(fp_poly
			(pts
				(xy 0.635 1.0668) (xy 0.635 -1.0668) (xy -0.635 -1.0668) (xy -0.635 1.0668)
			)
			(stroke
				(width 0)
				(type default)
			)
			(fill no)
			(layer "F.CrtYd")
		)
		(fp_line
			(start 0.254 -0.508)
			(end 0.254 0.508)
			(stroke
				(width 0.0254)
				(type default)
			)
			(layer "F.Fab")
		)
		(fp_line
			(start -0.254 -0.508)
			(end 0.254 -0.508)
			(stroke
				(width 0.0254)
				(type default)
			)
			(layer "F.Fab")
		)
		(fp_line
			(start 0.254 0.508)
			(end -0.254 0.508)
			(stroke
				(width 0.0254)
				(type default)
			)
			(layer "F.Fab")
		)
		(fp_line
			(start -0.254 0.508)
			(end -0.254 -0.508)
			(stroke
				(width 0.0254)
				(type default)
			)
			(layer "F.Fab")
		)
		(pad "1" smd rect
			(at 0 -0.4191 90)
			(size 0.508 0.5334)
			(layers "F.Cu" "F.Mask" "F.Paste")
			(net "DDR_VDDQ")
		)
		(pad "2" smd rect
			(at 0 0.4191 90)
			(size 0.508 0.5334)
			(layers "F.Cu" "F.Mask" "F.Paste")
			(net "GND")
		)
		(zone
			(layer "F.Cu")
			(hatch none 0.5)
			(connect_pads
				(clearance 0)
			)
			(min_thickness 0.25)
			(keepout
				(tracks not_allowed)
				(vias allowed)
				(pads allowed)
				(copperpour not_allowed)
				(footprints allowed)
			)
			(placement
				(enabled no)
				(sheetname "")
			)
			(fill
				(thermal_gap 0.5)
				(thermal_bridge_width 0.5)
				(island_removal_mode 0)
			)
			(polygon
				(pts
					(xy 73.3806 23.4696) (xy 73.4314 23.4696) (xy 73.4314 23.5204) (xy 73.3806 23.5204)
				)
			)
		)
	)
	(footprint ""
		(layer "F.Cu")
		(at 77.851 24.765)
		(property "Reference" "C264"
			(at 0 0 0)
			(layer "F.SilkS")
			(hide yes)
			(effects
				(font
					(size 1.27 1.27)
				)
			)
		)
		(property "Value" "1UF"
			(at -0.091846 0.2921 90)
			(unlocked yes)
			(layer "F.Fab")
			(hide yes)
			(effects
				(font
					(size 0.7874 0.5842)
					(thickness 0.2032)
				)
				(justify left)
			)
		)
		(property "Device Type" "CAPC0028"
			(at -0.091846 0.2921 90)
			(unlocked yes)
			(layer "F.Fab")
			(hide yes)
			(effects
				(font
					(size 0.7874 0.5842)
					(thickness 0.2032)
				)
				(justify left)
			)
		)
		(duplicate_pad_numbers_are_jumpers no)
		(fp_poly
			(pts
				(xy 0.635 1.0668) (xy 0.635 -1.0668) (xy -0.635 -1.0668) (xy -0.635 1.0668)
			)
			(stroke
				(width 0)
				(type default)
			)
			(fill no)
			(layer "F.CrtYd")
		)
		(fp_line
			(start -0.254 -0.508)
			(end 0.254 -0.508)
			(stroke
				(width 0.0254)
				(type default)
			)
			(layer "F.Fab")
		)
		(fp_line
			(start -0.254 0.508)
			(end -0.254 -0.508)
			(stroke
				(width 0.0254)
				(type default)
			)
			(layer "F.Fab")
		)
		(fp_line
			(start 0.254 -0.508)
			(end 0.254 0.508)
			(stroke
				(width 0.0254)
				(type default)
			)
			(layer "F.Fab")
		)
		(fp_line
			(start 0.254 0.508)
			(end -0.254 0.508)
			(stroke
				(width 0.0254)
				(type default)
			)
			(layer "F.Fab")
		)
		(pad "1" smd rect
			(at 0 -0.4191)
			(size 0.508 0.5334)
			(layers "F.Cu" "F.Mask" "F.Paste")
			(net "DDR0_32A_VREF1B")
		)
		(pad "2" smd rect
			(at 0 0.4191)
			(size 0.508 0.5334)
			(layers "F.Cu" "F.Mask" "F.Paste")
			(net "GND")
		)
		(zone
			(layer "F.Cu")
			(hatch none 0.5)
			(connect_pads
				(clearance 0)
			)
			(min_thickness 0.25)
			(keepout
				(tracks not_allowed)
				(vias allowed)
				(pads allowed)
				(copperpour not_allowed)
				(footprints allowed)
			)
			(placement
				(enabled no)
				(sheetname "")
			)
			(fill
				(thermal_gap 0.5)
				(thermal_bridge_width 0.5)
				(island_removal_mode 0)
			)
			(polygon
				(pts
					(xy 77.8764 24.7396) (xy 77.8764 24.7904) (xy 77.8256 24.7904) (xy 77.8256 24.7396)
				)
			)
		)
	)
	(footprint ""
		(layer "F.Cu")
		(at 64.516 52.07 90)
		(property "Reference" "C126"
			(at 0 0 90)
			(layer "F.SilkS")
			(hide yes)
			(effects
				(font
					(size 1.27 1.27)
				)
			)
		)
		(property "Value" "0.1UF"
			(at -0.091846 0.2921 180)
			(unlocked yes)
			(layer "F.Fab")
			(hide yes)
			(effects
				(font
					(size 0.7874 0.5842)
					(thickness 0.2032)
				)
				(justify left)
			)
		)
		(property "Device Type" "CAPC0073"
			(at -0.091846 0.2921 180)
			(unlocked yes)
			(layer "F.Fab")
			(hide yes)
			(effects
				(font
					(size 0.7874 0.5842)
					(thickness 0.2032)
				)
				(justify left)
			)
		)
		(duplicate_pad_numbers_are_jumpers no)
		(fp_poly
			(pts
				(xy 0.635 1.0668) (xy 0.635 -1.0668) (xy -0.635 -1.0668) (xy -0.635 1.0668)
			)
			(stroke
				(width 0)
				(type default)
			)
			(fill no)
			(layer "F.CrtYd")
		)
		(fp_line
			(start 0.254 -0.508)
			(end 0.254 0.508)
			(stroke
				(width 0.0254)
				(type default)
			)
			(layer "F.Fab")
		)
		(fp_line
			(start -0.254 -0.508)
			(end 0.254 -0.508)
			(stroke
				(width 0.0254)
				(type default)
			)
			(layer "F.Fab")
		)
		(fp_line
			(start 0.254 0.508)
			(end -0.254 0.508)
			(stroke
				(width 0.0254)
				(type default)
			)
			(layer "F.Fab")
		)
		(fp_line
			(start -0.254 0.508)
			(end -0.254 -0.508)
			(stroke
				(width 0.0254)
				(type default)
			)
			(layer "F.Fab")
		)
		(pad "1" smd rect
			(at 0 -0.4191 90)
			(size 0.508 0.5334)
			(layers "F.Cu" "F.Mask" "F.Paste")
			(net "EXT_12.0V")
		)
		(pad "2" smd rect
			(at 0 0.4191 90)
			(size 0.508 0.5334)
			(layers "F.Cu" "F.Mask" "F.Paste")
			(net "GND")
		)
		(zone
			(layer "F.Cu")
			(hatch none 0.5)
			(connect_pads
				(clearance 0)
			)
			(min_thickness 0.25)
			(keepout
				(tracks not_allowed)
				(vias allowed)
				(pads allowed)
				(copperpour not_allowed)
				(footprints allowed)
			)
			(placement
				(enabled no)
				(sheetname "")
			)
			(fill
				(thermal_gap 0.5)
				(thermal_bridge_width 0.5)
				(island_removal_mode 0)
			)
			(polygon
				(pts
					(xy 64.4906 52.0446) (xy 64.5414 52.0446) (xy 64.5414 52.0954) (xy 64.4906 52.0954)
				)
			)
		)
	)
	(footprint ""
		(layer "F.Cu")
		(at 65.405 41.5417 -90)
		(property "Reference" "L17"
			(at -4.93903 5.842 0)
			(unlocked yes)
			(layer "F.SilkS")
			(effects
				(font
					(size 0.7874 0.5842)
					(thickness 0.127)
				)
				(justify left)
			)
		)
		(property "Value" "300NH"
			(at -0.4826 1.121918 270)
			(unlocked yes)
			(layer "F.Fab")
			(hide yes)
			(effects
				(font
					(size 1.27 0.9652)
					(thickness 0.000001)
				)
				(justify left)
			)
		)
		(property "Device Type" "INDS0042"
			(at -0.4826 1.121918 270)
			(unlocked yes)
			(layer "F.Fab")
			(hide yes)
			(effects
				(font
					(size 1.27 0.9652)
					(thickness 0.000001)
				)
				(justify left)
			)
		)
		(duplicate_pad_numbers_are_jumpers no)
		(fp_line
			(start -4.191 5.842)
			(end -2.8956 5.842)
			(stroke
				(width 0.2032)
				(type default)
			)
			(layer "F.SilkS")
		)
		(fp_line
			(start -4.191 5.842)
			(end -1.524 5.842)
			(stroke
				(width 0.2032)
				(type default)
			)
			(layer "F.SilkS")
		)
		(fp_line
			(start 4.0259 5.842)
			(end 2.8702 5.842)
			(stroke
				(width 0.2032)
				(type default)
			)
			(layer "F.SilkS")
		)
		(fp_line
			(start 4.191 5.842)
			(end 1.524 5.842)
			(stroke
				(width 0.2032)
				(type default)
			)
			(layer "F.SilkS")
		)
		(fp_line
			(start -4.191 3.768369)
			(end -4.191 5.842)
			(stroke
				(width 0.2032)
				(type default)
			)
			(layer "F.SilkS")
		)
		(fp_line
			(start -4.191 1.4224)
			(end -4.191 2.581631)
			(stroke
				(width 0.2032)
				(type default)
			)
			(layer "F.SilkS")
		)
		(fp_line
			(start -4.191 -4.975225)
			(end -4.191 -2.4384)
			(stroke
				(width 0.2032)
				(type default)
			)
			(layer "F.SilkS")
		)
		(fp_line
			(start -4.191 -5.842)
			(end -4.191 5.842)
			(stroke
				(width 0.2032)
				(type default)
			)
			(layer "F.SilkS")
		)
		(fp_line
			(start -1.5367 -5.842)
			(end -3.346831 -5.842)
			(stroke
				(width 0.2032)
				(type default)
			)
			(layer "F.SilkS")
		)
		(fp_line
			(start -1.524 -5.842)
			(end -4.191 -5.842)
			(stroke
				(width 0.2032)
				(type default)
			)
			(layer "F.SilkS")
		)
		(fp_line
			(start 1.524 -5.842)
			(end 4.191 -5.842)
			(stroke
				(width 0.2032)
				(type default)
			)
			(layer "F.SilkS")
		)
		(fp_line
			(start 1.5367 -5.842)
			(end 4.191 -5.842)
			(stroke
				(width 0.2032)
				(type default)
			)
			(layer "F.SilkS")
		)
		(fp_line
			(start 4.191 -5.842)
			(end 4.191 5.842)
			(stroke
				(width 0.2032)
				(type default)
			)
			(layer "F.SilkS")
		)
		(fp_line
			(start 4.191 -5.842)
			(end 4.191 -1.7526)
			(stroke
				(width 0.2032)
				(type default)
			)
			(layer "F.SilkS")
		)
		(fp_poly
			(pts
				(xy -4.445 -6.096) (xy -1.778 -6.096) (xy -1.778 -6.35) (xy 1.778 -6.35) (xy 1.778 -6.096) (xy 4.445 -6.096)
				(xy 4.445 6.096) (xy 1.778 6.096) (xy 1.778 6.35) (xy -1.778 6.35) (xy -1.778 6.096) (xy -4.445 6.096)
			)
			(stroke
				(width 0)
				(type default)
			)
			(fill no)
			(layer "F.CrtYd")
		)
		(fp_line
			(start -3.8227 5.4991)
			(end 3.8227 5.4991)
			(stroke
				(width 0.2032)
				(type default)
			)
			(layer "F.Fab")
		)
		(fp_line
			(start 3.8227 5.4991)
			(end 3.8227 -5.4991)
			(stroke
				(width 0.2032)
				(type default)
			)
			(layer "F.Fab")
		)
		(fp_line
			(start -3.8227 -5.4991)
			(end -3.8227 5.4991)
			(stroke
				(width 0.2032)
				(type default)
			)
			(layer "F.Fab")
		)
		(fp_line
			(start 3.8227 -5.4991)
			(end -3.8227 -5.4991)
			(stroke
				(width 0.2032)
				(type default)
			)
			(layer "F.Fab")
		)
		(pad "1" smd rect
			(at 0 -4.1783 270)
			(size 2.3622 3.4036)
			(layers "F.Cu" "F.Mask" "F.Paste")
			(net "L_1_CORE_PHASE")
		)
		(pad "2" smd rect
			(at 0 4.1783 270)
			(size 2.3622 3.4036)
			(layers "F.Cu" "F.Mask" "F.Paste")
			(net "VDD_CORE")
		)
	)
)
